# BASEBOARD_FAB2 (Tioga Pass) — schematic netlist excerpt (pin names and nets, part order shuffled) for the footprints in the layout excerpt that follows; sources: Cadence DE-HDL packaged netlist, KiCad conversion of Wiwynn_Tioga_Pass_MB.brd

R1R22  RES  2.21K 1% CHIP  pkg 0402  page 188 : A = P3V3_STBY ; B = SMB_PCH_MEZZ_LOM3_SDA
C5G77  CAP  47UF 4V 20% X6S  pkg 0805  page 242 : A = PVDDQ_DEF ; B = GND
R6U5  RES  0.0 5% CHIP  pkg 0402  page 221 : A = PVDDQ_ABC ; B = VSENSE_PVDDQ_ABC_VTT

(kicad_pcb
	(version 20260206)
	(generator "pcbnew")
	(generator_version "10.0")
	(general
		(thickness 1.6)
		(legacy_teardrops no)
	)
	(paper "A4")
	(title_block
		(title "Wiwynn_Tioga_Pass_MB.brd")
		(comment 1 "Tioga Pass / footprints 2358-2360 of 4770")
	)
	(layers
		(0 "F.Cu" signal "TOP")
		(4 "In1.Cu" signal "L2GND")
		(6 "In2.Cu" signal "L3")
		(8 "In3.Cu" signal "L4GND")
		(10 "In4.Cu" signal "L5")
		(12 "In5.Cu" signal "L6GND")
		(14 "In6.Cu" signal "L7VCC")
		(16 "In7.Cu" signal "L8VCC")
		(18 "In8.Cu" signal "L9GND")
		(20 "In9.Cu" signal "L10")
		(22 "In10.Cu" signal "L11GND")
		(24 "In11.Cu" signal "L12")
		(26 "In12.Cu" signal "L13GND")
		(2 "B.Cu" signal "BOTTOM")
		(9 "F.Adhes" user "F.Adhesive")
		(11 "B.Adhes" user "B.Adhesive")
		(13 "F.Paste" user "Package Geometry/Pastemask Top")
		(15 "B.Paste" user "Package Geometry/Pastemask Bottom")
		(5 "F.SilkS" user "Ref Des/Silkscreen Top")
		(7 "B.SilkS" user "Ref Des/Silkscreen Bottom")
		(1 "F.Mask" user "Board Geometry/Soldermask Top")
		(3 "B.Mask" user "Board Geometry/Soldermask Bottom")
		(17 "Dwgs.User" user "User.Drawings")
		(19 "Cmts.User" user "User.Comments")
		(21 "Eco1.User" user "User.Eco1")
		(23 "Eco2.User" user "User.Eco2")
		(25 "Edge.Cuts" user "Board Geometry/Outline")
		(27 "Margin" user)
		(31 "F.CrtYd" user "Package Geometry/Place Bound Top")
		(29 "B.CrtYd" user "Package Geometry/Place Bound Bottom")
		(35 "F.Fab" user "Ref Des/Assembly Top")
		(33 "B.Fab" user "Ref Des/Assembly Bottom")
	)
	(footprint ""
		(layer "B.Cu")
		(at 182.736998 -5.321808)
		(property "Reference" "R6U5"
			(at 0 0 0)
			(layer "B.SilkS")
			(hide yes)
			(effects
				(font
					(size 1.27 1.27)
				)
				(justify mirror)
			)
		)
		(property "Value" ""
			(at 0 0 0)
			(layer "B.Fab")
			(effects
				(font
					(size 1.27 1.27)
				)
				(justify mirror)
			)
		)
		(duplicate_pad_numbers_are_jumpers no)
		(fp_rect
			(start 0.2794 0.9906)
			(end -0.2794 -0.1016)
			(stroke
				(width 0)
				(type default)
			)
			(fill no)
			(layer "B.CrtYd")
		)
		(fp_line
			(start -0.2794 -0.1016)
			(end 0.2794 -0.1016)
			(stroke
				(width 0.1)
				(type default)
			)
			(layer "B.Fab")
		)
		(fp_line
			(start -0.2794 0.9906)
			(end -0.2794 -0.1016)
			(stroke
				(width 0.1)
				(type default)
			)
			(layer "B.Fab")
		)
		(fp_line
			(start 0.2794 -0.1016)
			(end 0.2794 0.9906)
			(stroke
				(width 0.1)
				(type default)
			)
			(layer "B.Fab")
		)
		(fp_line
			(start 0.2794 0.9906)
			(end -0.2794 0.9906)
			(stroke
				(width 0.1)
				(type default)
			)
			(layer "B.Fab")
		)
		(pad "1" smd rect
			(at 0 0 180)
			(size 0.508 0.508)
			(layers "B.Cu" "B.Mask" "B.Paste")
			(net "PVDDQ_ABC")
		)
		(pad "2" smd rect
			(at 0 0.889 180)
			(size 0.508 0.508)
			(layers "B.Cu" "B.Mask" "B.Paste")
			(net "VSENSE_PVDDQ_ABC_VTT")
		)
		(zone
			(layer "B.Cu")
			(hatch none 0.5)
			(connect_pads
				(clearance 0)
			)
			(min_thickness 0.25)
			(keepout
				(tracks allowed)
				(vias not_allowed)
				(pads allowed)
				(copperpour not_allowed)
				(footprints allowed)
			)
			(placement
				(enabled no)
				(sheetname "")
			)
			(fill
				(thermal_gap 0.5)
				(thermal_bridge_width 0.5)
				(island_removal_mode 0)
			)
			(polygon
				(pts
					(xy 182.990998 -4.686808) (xy 182.990998 -5.067808) (xy 182.482998 -5.067808) (xy 182.482998 -4.686808)
				)
			)
		)
	)
	(footprint ""
		(layer "B.Cu")
		(at 259.09778 -149.7711 90)
		(property "Reference" "C5G77"
			(at -1.64973 0.78994 180)
			(unlocked yes)
			(layer "B.SilkS")
			(effects
				(font
					(size 0.7874 0.5842)
					(thickness 0.1524)
				)
				(justify mirror)
			)
		)
		(property "Value" ""
			(at 0 0 90)
			(layer "B.Fab")
			(effects
				(font
					(size 1.27 1.27)
				)
				(justify mirror)
			)
		)
		(duplicate_pad_numbers_are_jumpers no)
		(fp_rect
			(start -0.7239 -0.2159)
			(end 0.7239 1.9939)
			(stroke
				(width 0)
				(type default)
			)
			(fill no)
			(layer "B.CrtYd")
		)
		(fp_line
			(start 0.7239 -0.2159)
			(end 0.7239 1.9939)
			(stroke
				(width 0.1)
				(type default)
			)
			(layer "B.Fab")
		)
		(fp_line
			(start -0.7239 -0.2159)
			(end 0.7239 -0.2159)
			(stroke
				(width 0.1)
				(type default)
			)
			(layer "B.Fab")
		)
		(fp_line
			(start 0.7239 1.9939)
			(end -0.7239 1.9939)
			(stroke
				(width 0.1)
				(type default)
			)
			(layer "B.Fab")
		)
		(fp_line
			(start -0.7239 1.9939)
			(end -0.7239 -0.2159)
			(stroke
				(width 0.1)
				(type default)
			)
			(layer "B.Fab")
		)
		(pad "1" smd rect
			(at 0 0 270)
			(size 1.27 1.016)
			(layers "B.Cu" "B.Mask" "B.Paste")
			(net "PVDDQ_DEF")
		)
		(pad "2" smd rect
			(at 0 1.778 270)
			(size 1.27 1.016)
			(layers "B.Cu" "B.Mask" "B.Paste")
			(net "GND")
		)
		(zone
			(layer "B.Cu")
			(hatch none 0.5)
			(connect_pads
				(clearance 0)
			)
			(min_thickness 0.25)
			(keepout
				(tracks not_allowed)
				(vias allowed)
				(pads allowed)
				(copperpour not_allowed)
				(footprints allowed)
			)
			(placement
				(enabled no)
				(sheetname "")
			)
			(fill
				(thermal_gap 0.5)
				(thermal_bridge_width 0.5)
				(island_removal_mode 0)
			)
			(polygon
				(pts
					(xy 259.60578 -149.1361) (xy 260.36778 -149.1361) (xy 260.36778 -150.4061) (xy 259.60578 -150.4061)
				)
			)
		)
	)
	(footprint ""
		(layer "B.Cu")
		(at 470.027 -56.388 -90)
		(property "Reference" "R1R22"
			(at 0 0 90)
			(layer "B.SilkS")
			(hide yes)
			(effects
				(font
					(size 1.27 1.27)
				)
				(justify mirror)
			)
		)
		(property "Value" ""
			(at 0 0 90)
			(layer "B.Fab")
			(effects
				(font
					(size 1.27 1.27)
				)
				(justify mirror)
			)
		)
		(duplicate_pad_numbers_are_jumpers no)
		(fp_poly
			(pts
				(xy 0.2794 -0.1016) (xy -0.2794 -0.1016) (xy -0.2794 0.9906) (xy 0.2794 0.9906)
			)
			(stroke
				(width 0)
				(type default)
			)
			(fill no)
			(layer "B.CrtYd")
		)
		(fp_line
			(start -0.2794 0.9906)
			(end -0.2794 -0.1016)
			(stroke
				(width 0.1)
				(type default)
			)
			(layer "B.Fab")
		)
		(fp_line
			(start 0.2794 0.9906)
			(end -0.2794 0.9906)
			(stroke
				(width 0.1)
				(type default)
			)
			(layer "B.Fab")
		)
		(fp_line
			(start -0.2794 -0.1016)
			(end 0.2794 -0.1016)
			(stroke
				(width 0.1)
				(type default)
			)
			(layer "B.Fab")
		)
		(fp_line
			(start 0.2794 -0.1016)
			(end 0.2794 0.9906)
			(stroke
				(width 0.1)
				(type default)
			)
			(layer "B.Fab")
		)
		(pad "1" smd rect
			(at 0 0 90)
			(size 0.508 0.508)
			(layers "B.Cu" "B.Mask" "B.Paste")
			(net "P3V3_STBY")
		)
		(pad "2" smd rect
			(at 0 0.889 90)
			(size 0.508 0.508)
			(layers "B.Cu" "B.Mask" "B.Paste")
			(net "SMB_PCH_MEZZ_LOM3_SDA")
		)
		(zone
			(layer "B.Cu")
			(hatch none 0.5)
			(connect_pads
				(clearance 0)
			)
			(min_thickness 0.25)
			(keepout
				(tracks not_allowed)
				(vias allowed)
				(pads allowed)
				(copperpour not_allowed)
				(footprints allowed)
			)
			(placement
				(enabled no)
				(sheetname "")
			)
			(fill
				(thermal_gap 0.5)
				(thermal_bridge_width 0.5)
				(island_removal_mode 0)
			)
			(polygon
				(pts
					(xy 469.392 -56.134) (xy 469.392 -56.642) (xy 469.773 -56.642) (xy 469.773 -56.134)
				)
			)
		)
		(zone
			(layer "B.Cu")
			(hatch none 0.5)
			(connect_pads
				(clearance 0)
			)
			(min_thickness 0.25)
			(keepout
				(tracks allowed)
				(vias not_allowed)
				(pads allowed)
				(copperpour not_allowed)
				(footprints allowed)
			)
			(placement
				(enabled no)
				(sheetname "")
			)
			(fill
				(thermal_gap 0.5)
				(thermal_bridge_width 0.5)
				(island_removal_mode 0)
			)
			(polygon
				(pts
					(xy 469.773 -56.134) (xy 469.773 -56.642) (xy 469.392 -56.642) (xy 469.392 -56.134)
				)
			)
		)
	)
)
